(kicad_pcb
	(version 20260206)
	(generator "pcbnew")
	(generator_version "10.0")
	(general
		(thickness 1.6)
		(legacy_teardrops no)
	)
	(paper "A4")
	(title_block
		(title "Bryce Canyon_R.DPB_16317-1_OCP.brd")
		(comment 1 "Bryce Canyon / footprints 1165-1172 of 2099")
	)
	(layers
		(0 "F.Cu" signal "TOP")
		(4 "In1.Cu" signal "L2GND")
		(6 "In2.Cu" signal "L3")
		(8 "In3.Cu" signal "L4VCC")
		(10 "In4.Cu" signal "L5VCC")
		(12 "In5.Cu" signal "L6")
		(14 "In6.Cu" signal "L7GND")
		(2 "B.Cu" signal "BOTTOM")
		(9 "F.Adhes" user "F.Adhesive")
		(11 "B.Adhes" user "B.Adhesive")
		(13 "F.Paste" user "Package Geometry/Pastemask Top")
		(15 "B.Paste" user "Package Geometry/Pastemask Bottom")
		(5 "F.SilkS" user "Ref Des/Silkscreen Top")
		(7 "B.SilkS" user "Ref Des/Silkscreen Bottom")
		(1 "F.Mask" user "Board Geometry/Soldermask Top")
		(3 "B.Mask" user "Board Geometry/Soldermask Bottom")
		(17 "Dwgs.User" user "User.Drawings")
		(19 "Cmts.User" user "User.Comments")
		(21 "Eco1.User" user "User.Eco1")
		(23 "Eco2.User" user "User.Eco2")
		(25 "Edge.Cuts" user "Board Geometry/Outline")
		(27 "Margin" user)
		(31 "F.CrtYd" user "Package Geometry/Place Bound Top")
		(29 "B.CrtYd" user "Package Geometry/Place Bound Bottom")
		(35 "F.Fab" user "Ref Des/Assembly Top")
		(33 "B.Fab" user "Ref Des/Assembly Bottom")
	)
	(footprint ""
		(layer "F.Cu")
		(at 367.284 -246.761 180)
		(property "Reference" "R283"
			(at 0 0 180)
			(layer "F.SilkS")
			(hide yes)
			(effects
				(font
					(size 1.27 1.27)
				)
			)
		)
		(property "Value" "0R2J-2-GP"
			(at 0.064008 -3.993896 180)
			(unlocked yes)
			(layer "F.Fab")
			(hide yes)
			(effects
				(font
					(size 1.016 1.016)
					(thickness 0.1524)
				)
			)
		)
		(property "Device Type" "R402H16"
			(at 0.064008 -5.517896 180)
			(unlocked yes)
			(layer "F.Fab")
			(hide yes)
			(effects
				(font
					(size 1.016 1.016)
					(thickness 0.1524)
				)
			)
		)
		(duplicate_pad_numbers_are_jumpers no)
		(fp_line
			(start 0.508 -0.9398)
			(end -0.508 -0.9398)
			(stroke
				(width 0.1524)
				(type default)
			)
			(layer "F.SilkS")
		)
		(fp_line
			(start -0.508 -0.9398)
			(end -0.508 0.9398)
			(stroke
				(width 0.1524)
				(type default)
			)
			(layer "F.SilkS")
		)
		(fp_rect
			(start -0.508 0.9398)
			(end 0.508 -0.9398)
			(stroke
				(width 0)
				(type default)
			)
			(fill no)
			(layer "F.CrtYd")
		)
		(fp_rect
			(start -0.508 0.9398)
			(end 0.508 -0.9398)
			(stroke
				(width 0)
				(type default)
			)
			(fill no)
			(layer "F.Fab")
		)
		(pad "1" smd custom
			(at 0 -0.4445 180)
			(size 0.1397 0.1397)
			(layers "F.Cu" "F.Mask" "F.Paste")
			(net "SW_HDD_G7")
			(options
				(clearance outline)
				(anchor circle)
			)
			(primitives
				(gr_poly
					(pts
						(arc
							(start -0.1778 -0.2794)
							(mid -0.249642 -0.249642)
							(end -0.2794 -0.1778)
						)
						(arc
							(start -0.2794 0.1778)
							(mid -0.249642 0.249642)
							(end -0.1778 0.2794)
						)
						(arc
							(start 0.1778 0.2794)
							(mid 0.249642 0.249642)
							(end 0.2794 0.1778)
						)
						(arc
							(start 0.2794 -0.1778)
							(mid 0.249642 -0.249642)
							(end 0.1778 -0.2794)
						)
					)
					(width 0)
					(fill yes)
				)
			)
		)
		(pad "2" smd custom
			(at 0 0.4445 180)
			(size 0.1397 0.1397)
			(layers "F.Cu" "F.Mask" "F.Paste")
			(net "SW_HDD_R7")
			(options
				(clearance outline)
				(anchor circle)
			)
			(primitives
				(gr_poly
					(pts
						(arc
							(start -0.1778 -0.2794)
							(mid -0.249642 -0.249642)
							(end -0.2794 -0.1778)
						)
						(arc
							(start -0.2794 0.1778)
							(mid -0.249642 0.249642)
							(end -0.1778 0.2794)
						)
						(arc
							(start 0.1778 0.2794)
							(mid 0.249642 0.249642)
							(end 0.2794 0.1778)
						)
						(arc
							(start 0.2794 -0.1778)
							(mid 0.249642 -0.249642)
							(end 0.1778 -0.2794)
						)
					)
					(width 0)
					(fill yes)
				)
			)
		)
	)
	(footprint ""
		(layer "F.Cu")
		(at 187.866528 -370.137436 -90)
		(property "Reference" "Q216"
			(at 0 0 270)
			(layer "F.SilkS")
			(hide yes)
			(effects
				(font
					(size 1.27 1.27)
				)
			)
		)
		(property "Value" "2N7002KDW-GP"
			(at -2.3622 -8.2042 270)
			(unlocked yes)
			(layer "F.Fab")
			(hide yes)
			(effects
				(font
					(size 1.016 1.016)
					(thickness 0.1524)
				)
			)
		)
		(property "Device Type" "SOT-363H44"
			(at -2.3622 -10.1092 270)
			(unlocked yes)
			(layer "F.Fab")
			(hide yes)
			(effects
				(font
					(size 1.016 1.016)
					(thickness 0.1524)
				)
			)
		)
		(duplicate_pad_numbers_are_jumpers no)
		(fp_line
			(start -1.4478 1.7018)
			(end 1.4478 1.7018)
			(stroke
				(width 0.1524)
				(type default)
			)
			(layer "F.SilkS")
		)
		(fp_line
			(start 1.4478 1.7018)
			(end 1.4478 -1.7018)
			(stroke
				(width 0.1524)
				(type default)
			)
			(layer "F.SilkS")
		)
		(fp_line
			(start -1.27 1.524)
			(end -1.27 0.6604)
			(stroke
				(width 0.4826)
				(type default)
			)
			(layer "F.SilkS")
		)
		(fp_line
			(start -1.4478 -1.7018)
			(end -1.4478 1.7018)
			(stroke
				(width 0.1524)
				(type default)
			)
			(layer "F.SilkS")
		)
		(fp_line
			(start 1.4478 -1.7018)
			(end -1.4478 -1.7018)
			(stroke
				(width 0.1524)
				(type default)
			)
			(layer "F.SilkS")
		)
		(fp_poly
			(pts
				(xy -1.524 -1.778) (xy 1.524 -1.778) (xy 1.524 1.778) (xy -1.524 1.778)
			)
			(stroke
				(width 0)
				(type default)
			)
			(fill no)
			(layer "F.CrtYd")
		)
		(fp_poly
			(pts
				(xy -1.524 -1.778) (xy 1.524 -1.778) (xy 1.524 1.778) (xy -1.524 1.778)
			)
			(stroke
				(width 0)
				(type default)
			)
			(fill no)
			(layer "F.Fab")
		)
		(pad "1" smd rect
			(at -0.65024 0.9398 270)
			(size 0.4064 1.016)
			(layers "F.Cu" "F.Mask" "F.Paste")
			(net "GND")
		)
		(pad "2" smd rect
			(at 0 0.9398 270)
			(size 0.4064 1.016)
			(layers "F.Cu" "F.Mask" "F.Paste")
			(net "FAN_LED1_D")
		)
		(pad "3" smd rect
			(at 0.65024 0.9398 270)
			(size 0.4064 1.016)
			(layers "F.Cu" "F.Mask" "F.Paste")
			(net "FAN_LED1_D")
		)
		(pad "4" smd rect
			(at 0.65024 -0.9398 270)
			(size 0.4064 1.016)
			(layers "F.Cu" "F.Mask" "F.Paste")
			(net "GND")
		)
		(pad "5" smd rect
			(at 0 -0.9398 270)
			(size 0.4064 1.016)
			(layers "F.Cu" "F.Mask" "F.Paste")
			(net "FAN_LED1")
		)
		(pad "6" smd rect
			(at -0.65024 -0.9398 270)
			(size 0.4064 1.016)
			(layers "F.Cu" "F.Mask" "F.Paste")
			(net "FAN_LED1_D2")
		)
	)
	(footprint ""
		(layer "F.Cu")
		(at 430.403 -243.586 180)
		(property "Reference" "R310"
			(at 0 0 180)
			(layer "F.SilkS")
			(hide yes)
			(effects
				(font
					(size 1.27 1.27)
				)
			)
		)
		(property "Value" "0R2J-2-GP"
			(at 0.064008 -3.993896 180)
			(unlocked yes)
			(layer "F.Fab")
			(hide yes)
			(effects
				(font
					(size 1.016 1.016)
					(thickness 0.1524)
				)
			)
		)
		(property "Device Type" "R402H16"
			(at 0.064008 -5.517896 180)
			(unlocked yes)
			(layer "F.Fab")
			(hide yes)
			(effects
				(font
					(size 1.016 1.016)
					(thickness 0.1524)
				)
			)
		)
		(duplicate_pad_numbers_are_jumpers no)
		(fp_line
			(start 0.508 -0.9398)
			(end -0.508 -0.9398)
			(stroke
				(width 0.1524)
				(type default)
			)
			(layer "F.SilkS")
		)
		(fp_line
			(start -0.508 -0.9398)
			(end -0.508 0.9398)
			(stroke
				(width 0.1524)
				(type default)
			)
			(layer "F.SilkS")
		)
		(fp_rect
			(start -0.508 0.9398)
			(end 0.508 -0.9398)
			(stroke
				(width 0)
				(type default)
			)
			(fill no)
			(layer "F.CrtYd")
		)
		(fp_rect
			(start -0.508 0.9398)
			(end 0.508 -0.9398)
			(stroke
				(width 0)
				(type default)
			)
			(fill no)
			(layer "F.Fab")
		)
		(pad "1" smd custom
			(at 0 -0.4445 180)
			(size 0.1397 0.1397)
			(layers "F.Cu" "F.Mask" "F.Paste")
			(net "DRIVE_B_9_PWR")
			(options
				(clearance outline)
				(anchor circle)
			)
			(primitives
				(gr_poly
					(pts
						(arc
							(start -0.1778 -0.2794)
							(mid -0.249642 -0.249642)
							(end -0.2794 -0.1778)
						)
						(arc
							(start -0.2794 0.1778)
							(mid -0.249642 0.249642)
							(end -0.1778 0.2794)
						)
						(arc
							(start 0.1778 0.2794)
							(mid 0.249642 0.249642)
							(end 0.2794 0.1778)
						)
						(arc
							(start 0.2794 -0.1778)
							(mid 0.249642 -0.249642)
							(end 0.1778 -0.2794)
						)
					)
					(width 0)
					(fill yes)
				)
			)
		)
		(pad "2" smd custom
			(at 0 0.4445 180)
			(size 0.1397 0.1397)
			(layers "F.Cu" "F.Mask" "F.Paste")
			(net "SW_PWR_R_HDD9")
			(options
				(clearance outline)
				(anchor circle)
			)
			(primitives
				(gr_poly
					(pts
						(arc
							(start -0.1778 -0.2794)
							(mid -0.249642 -0.249642)
							(end -0.2794 -0.1778)
						)
						(arc
							(start -0.2794 0.1778)
							(mid -0.249642 0.249642)
							(end -0.1778 0.2794)
						)
						(arc
							(start 0.1778 0.2794)
							(mid 0.249642 0.249642)
							(end 0.2794 0.1778)
						)
						(arc
							(start 0.2794 -0.1778)
							(mid 0.249642 -0.249642)
							(end 0.1778 -0.2794)
						)
					)
					(width 0)
					(fill yes)
				)
			)
		)
	)
	(footprint ""
		(layer "F.Cu")
		(at 346.075 -214.376)
		(property "Reference" "R316"
			(at 0 0 0)
			(layer "F.SilkS")
			(hide yes)
			(effects
				(font
					(size 1.27 1.27)
				)
			)
		)
		(property "Value" "130R3F-GP"
			(at -0.0254 -2.5146 0)
			(unlocked yes)
			(layer "F.Fab")
			(hide yes)
			(effects
				(font
					(size 1.016 1.016)
					(thickness 0.1524)
				)
			)
		)
		(property "Device Type" "R603H22"
			(at -0.0254 -4.0386 0)
			(unlocked yes)
			(layer "F.Fab")
			(hide yes)
			(effects
				(font
					(size 1.016 1.016)
					(thickness 0.1524)
				)
			)
		)
		(duplicate_pad_numbers_are_jumpers no)
		(fp_line
			(start -0.4826 0)
			(end -0.2032 0)
			(stroke
				(width 0.2032)
				(type default)
			)
			(layer "F.SilkS")
		)
		(fp_line
			(start 0.2032 0)
			(end 0.4826 0)
			(stroke
				(width 0.2032)
				(type default)
			)
			(layer "F.SilkS")
		)
		(fp_rect
			(start -0.5842 1.3335)
			(end 0.5842 -1.3335)
			(stroke
				(width 0)
				(type default)
			)
			(fill no)
			(layer "F.CrtYd")
		)
		(fp_rect
			(start -0.5842 1.3335)
			(end 0.5842 -1.3335)
			(stroke
				(width 0)
				(type default)
			)
			(fill no)
			(layer "F.Fab")
		)
		(pad "1" smd custom
			(at 0 -0.762)
			(size 0.2159 0.2159)
			(layers "F.Cu" "F.Mask" "F.Paste")
			(net "P5V_B_3")
			(options
				(clearance outline)
				(anchor circle)
			)
			(primitives
				(gr_poly
					(pts
						(arc
							(start -0.3302 -0.4318)
							(mid -0.402042 -0.402042)
							(end -0.4318 -0.3302)
						)
						(arc
							(start -0.4318 0.3302)
							(mid -0.402042 0.402042)
							(end -0.3302 0.4318)
						)
						(arc
							(start 0.3302 0.4318)
							(mid 0.402042 0.402042)
							(end 0.4318 0.3302)
						)
						(arc
							(start 0.4318 -0.3302)
							(mid 0.402042 -0.402042)
							(end 0.3302 -0.4318)
						)
					)
					(width 0)
					(fill yes)
				)
			)
		)
		(pad "2" smd custom
			(at 0 0.762)
			(size 0.2159 0.2159)
			(layers "F.Cu" "F.Mask" "F.Paste")
			(net "FLT_HDD7")
			(options
				(clearance outline)
				(anchor circle)
			)
			(primitives
				(gr_poly
					(pts
						(arc
							(start -0.3302 -0.4318)
							(mid -0.402042 -0.402042)
							(end -0.4318 -0.3302)
						)
						(arc
							(start -0.4318 0.3302)
							(mid -0.402042 0.402042)
							(end -0.3302 0.4318)
						)
						(arc
							(start 0.3302 0.4318)
							(mid 0.402042 0.402042)
							(end 0.4318 0.3302)
						)
						(arc
							(start 0.4318 -0.3302)
							(mid 0.402042 -0.402042)
							(end 0.3302 -0.4318)
						)
					)
					(width 0)
					(fill yes)
				)
			)
		)
	)
	(footprint ""
		(layer "F.Cu")
		(at 33.3248 -63.799974)
		(property "Reference" ""
			(at 0 0 0)
			(layer "F.SilkS")
			(hide yes)
			(effects
				(font
					(size 1.27 1.27)
				)
			)
		)
		(property "Value" "*"
			(at -8.398764 -8.057642 0)
			(unlocked yes)
			(layer "F.Fab")
			(hide yes)
			(effects
				(font
					(size 1.016 1.016)
					(thickness 0.1524)
				)
			)
		)
		(duplicate_pad_numbers_are_jumpers no)
		(fp_poly
			(pts
				(arc
					(start 7.3152 0)
					(mid 0 7.3152)
					(end -7.3152 0)
				)
				(arc
					(start -7.3152 -5.9944)
					(mid 0 -13.3096)
					(end 7.3152 -5.9944)
				)
			)
			(stroke
				(width 0)
				(type default)
			)
			(fill no)
			(layer "B.CrtYd")
		)
		(fp_poly
			(pts
				(arc
					(start 7.3152 0)
					(mid 0 7.3152)
					(end -7.3152 0)
				)
				(arc
					(start -7.3152 -5.9944)
					(mid 0 -13.3096)
					(end 7.3152 -5.9944)
				)
			)
			(stroke
				(width 0)
				(type default)
			)
			(fill no)
			(layer "F.CrtYd")
		)
		(fp_poly
			(pts
				(arc
					(start 7.3152 0)
					(mid 0 7.3152)
					(end -7.3152 0)
				)
				(arc
					(start -7.3152 -5.9944)
					(mid 0 -13.3096)
					(end 7.3152 -5.9944)
				)
			)
			(stroke
				(width 0)
				(type default)
			)
			(fill no)
			(layer "B.Fab")
		)
		(fp_poly
			(pts
				(arc
					(start 7.3152 0)
					(mid 0 7.3152)
					(end -7.3152 0)
				)
				(arc
					(start -7.3152 -5.9944)
					(mid 0 -13.3096)
					(end 7.3152 -5.9944)
				)
			)
			(stroke
				(width 0)
				(type default)
			)
			(fill no)
			(layer "F.Fab")
		)
		(pad "1" thru_hole oval
			(at 0 0)
			(size 14.0208 20.0152)
			(drill 0.0254
				(offset 0 -2.9972)
			)
			(layers "*.Cu" "*.Mask")
			(remove_unused_layers no)
			(net "Net_11")
			(clearance -1.002284)
			(thermal_gap 0.1524)
			(padstack
				(mode front_inner_back)
				(layer "Inner"
					(shape custom)
					(size 2.928012 2.928012)
					(options
						(anchor circle)
					)
					(primitives
						(gr_poly
							(pts
								(arc
									(start 4.571746 -2.084324)
									(mid 0.000333 7.430372)
									(end -4.571492 -2.084324)
								)
								(arc
									(start -4.571492 -2.084324)
									(mid -3.570296 -3.611977)
									(end -2.875026 -5.30098)
								)
								(arc
									(start -2.875026 -5.30098)
									(mid 0.000217 -7.43089)
									(end 2.87528 -5.30098)
								)
								(arc
									(start 2.87528 -5.30098)
									(mid 3.570511 -3.611956)
									(end 4.571746 -2.084324)
								)
							)
							(width 0)
							(fill yes)
						)
					)
					(clearance 0.1524)
				)
				(layer "B.Cu"
					(shape oval)
					(size 14.0208 20.0152)
					(offset 0 -2.9972)
					(clearance -1.002284)
				)
			)
		)
		(zone
			(layers "F.Cu" "B.Cu" "In1.Cu" "In2.Cu" "In3.Cu" "In4.Cu" "In5.Cu" "In6.Cu")
			(hatch none 0.5)
			(connect_pads
				(clearance 0)
			)
			(min_thickness 0.25)
			(keepout
				(tracks not_allowed)
				(vias allowed)
				(pads allowed)
				(copperpour not_allowed)
				(footprints allowed)
			)
			(placement
				(enabled no)
				(sheetname "")
			)
			(fill
				(thermal_gap 0.5)
				(thermal_bridge_width 0.5)
				(island_removal_mode 0)
			)
			(polygon
				(pts
					(arc
						(start 26.3144 -69.794374)
						(mid 33.3248 -76.804774)
						(end 40.3352 -69.794374)
					)
					(arc
						(start 40.3352 -63.799974)
						(mid 33.3248 -56.789574)
						(end 26.3144 -63.799974)
					)
				)
			)
		)
	)
	(footprint ""
		(layer "F.Cu")
		(at 445.415924 -154.70505)
		(property "Reference" "TP131"
			(at 0 0 0)
			(layer "F.SilkS")
			(hide yes)
			(effects
				(font
					(size 1.27 1.27)
				)
			)
		)
		(property "Value" "*"
			(at -0.0508 -1.6764 0)
			(unlocked yes)
			(layer "F.Fab")
			(hide yes)
			(effects
				(font
					(size 1.016 1.016)
					(thickness 0.1524)
				)
			)
		)
		(property "Device Type" "TPAD32"
			(at -0.0508 -3.2004 0)
			(unlocked yes)
			(layer "F.Fab")
			(hide yes)
			(effects
				(font
					(size 1.016 1.016)
					(thickness 0.1524)
				)
			)
		)
		(duplicate_pad_numbers_are_jumpers no)
		(fp_poly
			(pts
				(arc
					(start 0.4064 0)
					(mid -0.4064 0)
					(end 0.4064 0)
				)
			)
			(stroke
				(width 0)
				(type default)
			)
			(fill no)
			(layer "F.CrtYd")
		)
		(fp_poly
			(pts
				(arc
					(start 0.7112 0)
					(mid -0.7112 0)
					(end 0.7112 0)
				)
			)
			(stroke
				(width 0)
				(type default)
			)
			(fill no)
			(layer "F.Fab")
		)
		(pad "1" smd circle
			(at 0 0)
			(size 0.8128 0.8128)
			(layers "F.Cu" "F.Mask" "F.Paste")
			(net "ACT_HDD_22")
		)
	)
	(footprint ""
		(layer "F.Cu")
		(at 150.114 -272.288)
		(property "Reference" "C87"
			(at 0 0 0)
			(layer "F.SilkS")
			(hide yes)
			(effects
				(font
					(size 1.27 1.27)
				)
			)
		)
		(property "Value" "SC4D7U25V5KX-1-GP"
			(at -0.0762 -6.1214 0)
			(unlocked yes)
			(layer "F.Fab")
			(hide yes)
			(effects
				(font
					(size 1.016 1.016)
					(thickness 0.1524)
				)
			)
		)
		(property "Device Type" "C805H58"
			(at -0.0762 -8.1534 0)
			(unlocked yes)
			(layer "F.Fab")
			(hide yes)
			(effects
				(font
					(size 1.016 1.016)
					(thickness 0.1524)
				)
			)
		)
		(duplicate_pad_numbers_are_jumpers no)
		(fp_line
			(start 0.635 0)
			(end -0.635 0)
			(stroke
				(width 0.508)
				(type default)
			)
			(layer "F.SilkS")
		)
		(fp_rect
			(start -0.9652 1.778)
			(end 0.9652 -1.778)
			(stroke
				(width 0)
				(type default)
			)
			(fill no)
			(layer "F.CrtYd")
		)
		(fp_poly
			(pts
				(xy -0.9652 -1.778) (xy 0.9652 -1.778) (xy 0.9652 1.778) (xy -0.9652 1.778)
			)
			(stroke
				(width 0)
				(type default)
			)
			(fill no)
			(layer "F.Fab")
		)
		(pad "1" smd rect
			(at 0 -0.9652)
			(size 1.397 1.143)
			(layers "F.Cu" "F.Mask" "F.Paste")
			(net "P12V_HDD4")
		)
		(pad "2" smd rect
			(at 0 0.9652)
			(size 1.397 1.143)
			(layers "F.Cu" "F.Mask" "F.Paste")
			(net "GND")
		)
	)
	(footprint ""
		(layer "F.Cu")
		(at 349.7834 -146.3548)
		(property "Reference" "R511"
			(at 0 0 0)
			(layer "F.SilkS")
			(hide yes)
			(effects
				(font
					(size 1.27 1.27)
				)
			)
		)
		(property "Value" "220R3F-1-GP"
			(at -0.0254 -2.5146 0)
			(unlocked yes)
			(layer "F.Fab")
			(hide yes)
			(effects
				(font
					(size 1.016 1.016)
					(thickness 0.1524)
				)
			)
		)
		(property "Device Type" "R603H22"
			(at -0.0254 -4.0386 0)
			(unlocked yes)
			(layer "F.Fab")
			(hide yes)
			(effects
				(font
					(size 1.016 1.016)
					(thickness 0.1524)
				)
			)
		)
		(duplicate_pad_numbers_are_jumpers no)
		(fp_line
			(start -0.4826 0)
			(end -0.2032 0)
			(stroke
				(width 0.2032)
				(type default)
			)
			(layer "F.SilkS")
		)
		(fp_line
			(start 0.2032 0)
			(end 0.4826 0)
			(stroke
				(width 0.2032)
				(type default)
			)
			(layer "F.SilkS")
		)
		(fp_rect
			(start -0.5842 1.3335)
			(end 0.5842 -1.3335)
			(stroke
				(width 0)
				(type default)
			)
			(fill no)
			(layer "F.CrtYd")
		)
		(fp_rect
			(start -0.5842 1.3335)
			(end 0.5842 -1.3335)
			(stroke
				(width 0)
				(type default)
			)
			(fill no)
			(layer "F.Fab")
		)
		(pad "1" smd custom
			(at 0 -0.762)
			(size 0.2159 0.2159)
			(layers "F.Cu" "F.Mask" "F.Paste")
			(net "HDD_PRSNT_19")
			(options
				(clearance outline)
				(anchor circle)
			)
			(primitives
				(gr_poly
					(pts
						(arc
							(start -0.3302 -0.4318)
							(mid -0.402042 -0.402042)
							(end -0.4318 -0.3302)
						)
						(arc
							(start -0.4318 0.3302)
							(mid -0.402042 0.402042)
							(end -0.3302 0.4318)
						)
						(arc
							(start 0.3302 0.4318)
							(mid 0.402042 0.402042)
							(end 0.4318 0.3302)
						)
						(arc
							(start 0.4318 -0.3302)
							(mid 0.402042 -0.402042)
							(end 0.3302 -0.4318)
						)
					)
					(width 0)
					(fill yes)
				)
			)
		)
		(pad "2" smd custom
			(at 0 0.762)
			(size 0.2159 0.2159)
			(layers "F.Cu" "F.Mask" "F.Paste")
			(net "DRIVE_B_19_INS")
			(options
				(clearance outline)
				(anchor circle)
			)
			(primitives
				(gr_poly
					(pts
						(arc
							(start -0.3302 -0.4318)
							(mid -0.402042 -0.402042)
							(end -0.4318 -0.3302)
						)
						(arc
							(start -0.4318 0.3302)
							(mid -0.402042 0.402042)
							(end -0.3302 0.4318)
						)
						(arc
							(start 0.3302 0.4318)
							(mid 0.402042 0.402042)
							(end 0.4318 0.3302)
						)
						(arc
							(start 0.4318 -0.3302)
							(mid 0.402042 -0.402042)
							(end 0.3302 -0.4318)
						)
					)
					(width 0)
					(fill yes)
				)
			)
		)
	)
)
